#ISCELL
  pure_quanta quanta_title_block_c *
  *
#CELL
  pure_quanta q_cap *
  page68_i1
#CELL
  pure_quanta q_cap *
  page68_i10
#CELL
  pure_quanta q_cap *
  page68_i100
#CELL
  pure_quanta q_cap *
  page68_i101
#CELL
  pure_quanta q_cap *
  page68_i102
#CELL
  pure_quanta q_cap *
  page68_i103
#CELL
  pure_quanta q_cap *
  page68_i104
#CELL
  pure_quanta q_cap *
  page68_i105
#CELL
  pure_quanta q_cap *
  page68_i106
#ISCELL
  pure_quanta_power universal_gnd *
  page68_i107
#CELL
  pure_quanta q_cap *
  page68_i108
#CELL
  pure_quanta q_cap *
  page68_i109
#ISCELL
  pure_quanta_power universal_power *
  page68_i11
#CELL
  pure_quanta q_cap *
  page68_i110
#CELL
  pure_quanta q_cap *
  page68_i12
#ISCELL
  pure_quanta_power universal_power *
  page68_i13
#CELL
  pure_quanta q_cap *
  page68_i14
#CELL
  pure_quanta q_cap *
  page68_i15
#CELL
  pure_quanta q_cap *
  page68_i16
#CELL
  pure_quanta q_cap *
  page68_i17
#ISCELL
  pure_quanta_power universal_gnd *
  page68_i18
#CELL
  pure_quanta q_cap *
  page68_i19
#CELL
  pure_quanta q_cap *
  page68_i2
#CELL
  pure_quanta q_cap *
  page68_i20
#CELL
  pure_quanta q_cap *
  page68_i21
#CELL
  pure_quanta q_cap *
  page68_i22
#CELL
  pure_quanta q_cap *
  page68_i23
#CELL
  pure_quanta q_cap *
  page68_i24
#CELL
  pure_quanta q_cap *
  page68_i25
#CELL
  pure_quanta q_cap *
  page68_i26
#CELL
  pure_quanta q_cap *
  page68_i27
#CELL
  pure_quanta q_cap *
  page68_i28
#CELL
  pure_quanta q_cap *
  page68_i29
#ISCELL
  pure_quanta_power universal_power *
  page68_i3
#CELL
  pure_quanta q_cap *
  page68_i30
#CELL
  pure_quanta q_cap *
  page68_i31
#CELL
  pure_quanta q_cap *
  page68_i32
#CELL
  pure_quanta q_cap *
  page68_i33
#CELL
  pure_quanta q_cap *
  page68_i34
#ISCELL
  pure_quanta_power universal_gnd *
  page68_i35
#CELL
  pure_quanta q_cap *
  page68_i36
#ISCELL
  pure_quanta_power universal_power *
  page68_i37
#CELL
  pure_quanta q_cap *
  page68_i38
#ISCELL
  pure_quanta_power universal_gnd *
  page68_i39
#CELL
  pure_quanta q_cap *
  page68_i4
#CELL
  pure_quanta q_cap *
  page68_i40
#ISCELL
  pure_quanta_power universal_gnd *
  page68_i41
#ISCELL
  pure_quanta_power universal_power *
  page68_i42
#CELL
  pure_quanta q_cap *
  page68_i43
#ISCELL
  pure_quanta_power universal_power *
  page68_i44
#CELL
  pure_quanta q_cap *
  page68_i45
#CELL
  pure_quanta q_cap *
  page68_i46
#CELL
  pure_quanta q_cap *
  page68_i47
#CELL
  pure_quanta q_cap *
  page68_i48
#CELL
  pure_quanta q_cap *
  page68_i49
#CELL
  pure_quanta q_cap *
  page68_i5
#CELL
  pure_quanta q_cap *
  page68_i50
#CELL
  pure_quanta q_cap *
  page68_i51
#CELL
  pure_quanta q_cap *
  page68_i52
#CELL
  pure_quanta q_cap *
  page68_i53
#CELL
  pure_quanta q_cap *
  page68_i54
#CELL
  pure_quanta q_cap *
  page68_i55
#CELL
  pure_quanta q_cap *
  page68_i56
#CELL
  pure_quanta q_cap *
  page68_i57
#CELL
  pure_quanta q_cap *
  page68_i58
#ISCELL
  pure_quanta_power universal_gnd *
  page68_i59
#ISCELL
  pure_quanta_power universal_power *
  page68_i6
#CELL
  pure_quanta q_cap *
  page68_i60
#ISCELL
  pure_quanta_power universal_power *
  page68_i61
#CELL
  pure_quanta q_cap *
  page68_i62
#CELL
  pure_quanta q_cap *
  page68_i63
#ISCELL
  pure_quanta_power universal_power *
  page68_i64
#CELL
  pure_quanta q_cap *
  page68_i65
#CELL
  pure_quanta q_cap *
  page68_i66
#CELL
  pure_quanta q_cap *
  page68_i67
#ISCELL
  pure_quanta_power universal_gnd *
  page68_i68
#CELL
  pure_quanta q_cap *
  page68_i69
#CELL
  pure_quanta q_cap *
  page68_i7
#CELL
  pure_quanta q_cap *
  page68_i70
#CELL
  pure_quanta q_cap *
  page68_i71
#CELL
  pure_quanta q_cap *
  page68_i72
#CELL
  pure_quanta q_cap *
  page68_i73
#CELL
  pure_quanta q_cap *
  page68_i74
#CELL
  pure_quanta q_cap *
  page68_i75
#CELL
  pure_quanta q_cap *
  page68_i76
#CELL
  pure_quanta q_cap *
  page68_i77
#CELL
  pure_quanta q_cap *
  page68_i78
#CELL
  pure_quanta q_cap *
  page68_i79
#ISCELL
  pure_quanta_power universal_power *
  page68_i8
#CELL
  pure_quanta q_cap *
  page68_i80
#CELL
  pure_quanta q_cap *
  page68_i81
#CELL
  pure_quanta q_cap *
  page68_i82
#CELL
  pure_quanta q_cap *
  page68_i83
#CELL
  pure_quanta q_cap *
  page68_i84
#ISCELL
  pure_quanta_power universal_gnd *
  page68_i85
#CELL
  pure_quanta q_cap *
  page68_i86
#CELL
  pure_quanta q_cap *
  page68_i87
#ISCELL
  pure_quanta_power universal_gnd *
  page68_i88
#CELL
  pure_quanta q_cap *
  page68_i89
#CELL
  pure_quanta q_cap *
  page68_i9
#ISCELL
  pure_quanta_power universal_gnd *
  page68_i90
#CELL
  pure_quanta q_cap *
  page68_i91
#CELL
  pure_quanta q_cap *
  page68_i92
#CELL
  pure_quanta q_cap *
  page68_i93
#CELL
  pure_quanta q_cap *
  page68_i94
#CELL
  pure_quanta q_cap *
  page68_i95
#CELL
  pure_quanta q_cap *
  page68_i96
#CELL
  pure_quanta q_cap *
  page68_i97
#CELL
  pure_quanta q_cap *
  page68_i98
#CELL
  pure_quanta q_cap *
  page68_i99
